(kicad_pcb
	(version 20260206)
	(generator "pcbnew")
	(generator_version "10.0")
	(general
		(thickness 1.6)
		(legacy_teardrops no)
	)
	(paper "A4")
	(title_block
		(title "timecard-production-celestica-r4006 — R4006-B0001-02_R01.brd")
		(comment 1 "Time Appliance Project (Time Card) / footprints 499-503 of 1113")
	)
	(layers
		(0 "F.Cu" signal "TOP")
		(4 "In1.Cu" signal "L02_GND1")
		(6 "In2.Cu" signal "L03_SIG1")
		(8 "In3.Cu" signal "L04_GND2")
		(10 "In4.Cu" signal "L05_VCC1")
		(12 "In5.Cu" signal "L06_VCC2")
		(14 "In6.Cu" signal "L07_GND3")
		(16 "In7.Cu" signal "L08_SIG2")
		(18 "In8.Cu" signal "L09_GND4")
		(2 "B.Cu" signal "BOTTOM")
		(9 "F.Adhes" user "F.Adhesive")
		(11 "B.Adhes" user "B.Adhesive")
		(13 "F.Paste" user "Package Geometry/Pastemask Top")
		(15 "B.Paste" user "Package Geometry/Pastemask Bottom")
		(5 "F.SilkS" user "Ref Des/Silkscreen Top")
		(7 "B.SilkS" user "Ref Des/Silkscreen Bottom")
		(1 "F.Mask" user "Board Geometry/Soldermask Top")
		(3 "B.Mask" user "Board Geometry/Soldermask Bottom")
		(17 "Dwgs.User" user "User.Drawings")
		(19 "Cmts.User" user "User.Comments")
		(21 "Eco1.User" user "User.Eco1")
		(23 "Eco2.User" user "User.Eco2")
		(25 "Edge.Cuts" user "Board Geometry/Outline")
		(27 "Margin" user)
		(31 "F.CrtYd" user "Package Geometry/Place Bound Top")
		(29 "B.CrtYd" user "Package Geometry/Place Bound Bottom")
		(35 "F.Fab" user "Ref Des/Assembly Top")
		(33 "B.Fab" user "Ref Des/Assembly Bottom")
	)
	(footprint ""
		(layer "F.Cu")
		(at 128.27 -98.298 -90)
		(property "Reference" "C72"
			(at -2.921 -1.43637 90)
			(unlocked yes)
			(layer "F.SilkS")
			(effects
				(font
					(size 0.7874 0.5842)
					(thickness 0.1524)
				)
			)
		)
		(property "Value" "VAL*"
			(at 0.0762 3.134106 270)
			(unlocked yes)
			(layer "F.Fab")
			(hide yes)
			(effects
				(font
					(size 0.7874 0.5842)
					(thickness 0.1524)
				)
			)
		)
		(property "Device Type" "CAPACITOR-G107-0F106-EM,10UF,2A"
			(at 0.0508 2.194306 270)
			(unlocked yes)
			(layer "F.Fab")
			(hide yes)
			(effects
				(font
					(size 0.7874 0.5842)
					(thickness 0.1524)
				)
			)
		)
		(property "User Part Number" "PARTNUM*"
			(at 0.1016 5.013706 270)
			(unlocked yes)
			(layer "Cmts.User")
			(hide yes)
			(effects
				(font
					(size 0.7874 0.5842)
					(thickness 0.1524)
				)
			)
		)
		(property "Tolerance" "TOL*"
			(at 0.0762 4.048506 270)
			(unlocked yes)
			(layer "Cmts.User")
			(hide yes)
			(effects
				(font
					(size 0.7874 0.5842)
					(thickness 0.1524)
				)
			)
		)
		(duplicate_pad_numbers_are_jumpers no)
		(fp_line
			(start -1.5748 0.9398)
			(end 1.5748 0.9398)
			(stroke
				(width 0.1)
				(type default)
			)
			(layer "F.SilkS")
		)
		(fp_line
			(start 1.5748 0.9398)
			(end 1.5748 -0.9398)
			(stroke
				(width 0.1)
				(type default)
			)
			(layer "F.SilkS")
		)
		(fp_line
			(start -1.5748 -0.9398)
			(end -1.5748 0.9398)
			(stroke
				(width 0.1)
				(type default)
			)
			(layer "F.SilkS")
		)
		(fp_line
			(start 1.5748 -0.9398)
			(end -1.5748 -0.9398)
			(stroke
				(width 0.1)
				(type default)
			)
			(layer "F.SilkS")
		)
		(fp_rect
			(start 1.5748 0.9398)
			(end -1.5748 -0.9398)
			(stroke
				(width 0)
				(type default)
			)
			(fill no)
			(layer "F.CrtYd")
		)
		(fp_line
			(start -1.016 0.635)
			(end 1.016 0.635)
			(stroke
				(width 0.1)
				(type default)
			)
			(layer "F.Fab")
		)
		(fp_line
			(start 1.016 0.635)
			(end 1.016 -0.635)
			(stroke
				(width 0.1)
				(type default)
			)
			(layer "F.Fab")
		)
		(fp_line
			(start -1.016 -0.635)
			(end -1.016 0.635)
			(stroke
				(width 0.1)
				(type default)
			)
			(layer "F.Fab")
		)
		(fp_line
			(start 1.016 -0.635)
			(end -1.016 -0.635)
			(stroke
				(width 0.1)
				(type default)
			)
			(layer "F.Fab")
		)
		(pad "1" smd rect
			(at -0.8382 0 270)
			(size 0.9652 1.3716)
			(layers "F.Cu" "F.Mask" "F.Paste")
			(net "XP5R0V_VCC_ANT")
		)
		(pad "2" smd rect
			(at 0.8382 0 270)
			(size 0.9652 1.3716)
			(layers "F.Cu" "F.Mask" "F.Paste")
			(net "SG")
		)
		(zone
			(layer "F.Cu")
			(hatch none 0.5)
			(connect_pads
				(clearance 0)
			)
			(min_thickness 0.25)
			(keepout
				(tracks allowed)
				(vias not_allowed)
				(pads allowed)
				(copperpour not_allowed)
				(footprints allowed)
			)
			(placement
				(enabled no)
				(sheetname "")
			)
			(fill
				(thermal_gap 0.5)
				(thermal_bridge_width 0.5)
				(island_removal_mode 0)
			)
			(polygon
				(pts
					(xy 127.635 -98.0694) (xy 128.905 -98.0694) (xy 128.905 -98.5266) (xy 127.635 -98.5266)
				)
			)
		)
	)
	(footprint ""
		(layer "F.Cu")
		(at 129.794 -95.885 180)
		(property "Reference" "C272"
			(at -0.127 -1.69037 0)
			(unlocked yes)
			(layer "F.SilkS")
			(effects
				(font
					(size 0.7874 0.5842)
					(thickness 0.1524)
				)
			)
		)
		(property "Value" "VAL*"
			(at 0.0762 2.067306 180)
			(unlocked yes)
			(layer "F.Fab")
			(hide yes)
			(effects
				(font
					(size 0.7874 0.5842)
					(thickness 0.1524)
				)
			)
		)
		(property "Device Type" "CAPACITOR-G105-0B104-EK,0.1UF,A"
			(at 0.0508 1.127506 180)
			(unlocked yes)
			(layer "F.Fab")
			(hide yes)
			(effects
				(font
					(size 0.7874 0.5842)
					(thickness 0.1524)
				)
			)
		)
		(property "User Part Number" "PARTNUM*"
			(at 0.1016 4.023106 180)
			(unlocked yes)
			(layer "Cmts.User")
			(hide yes)
			(effects
				(font
					(size 0.7874 0.5842)
					(thickness 0.1524)
				)
			)
		)
		(property "Tolerance" "TOL*"
			(at 0.0762 3.032506 180)
			(unlocked yes)
			(layer "Cmts.User")
			(hide yes)
			(effects
				(font
					(size 0.7874 0.5842)
					(thickness 0.1524)
				)
			)
		)
		(duplicate_pad_numbers_are_jumpers no)
		(fp_line
			(start 1.143 0.5588)
			(end 1.143 -0.5588)
			(stroke
				(width 0.1)
				(type default)
			)
			(layer "F.SilkS")
		)
		(fp_line
			(start 1.143 -0.5588)
			(end -1.143 -0.5588)
			(stroke
				(width 0.1)
				(type default)
			)
			(layer "F.SilkS")
		)
		(fp_line
			(start -1.143 0.5588)
			(end 1.143 0.5588)
			(stroke
				(width 0.1)
				(type default)
			)
			(layer "F.SilkS")
		)
		(fp_line
			(start -1.143 -0.5588)
			(end -1.143 0.5588)
			(stroke
				(width 0.1)
				(type default)
			)
			(layer "F.SilkS")
		)
		(fp_rect
			(start -1.143 0.5588)
			(end 1.143 -0.5588)
			(stroke
				(width 0)
				(type default)
			)
			(fill no)
			(layer "F.CrtYd")
		)
		(fp_line
			(start 0.508 0.3048)
			(end 0.508 -0.3048)
			(stroke
				(width 0.1)
				(type default)
			)
			(layer "F.Fab")
		)
		(fp_line
			(start 0.508 -0.3048)
			(end -0.508 -0.3048)
			(stroke
				(width 0.1)
				(type default)
			)
			(layer "F.Fab")
		)
		(fp_line
			(start -0.508 0.3048)
			(end 0.508 0.3048)
			(stroke
				(width 0.1)
				(type default)
			)
			(layer "F.Fab")
		)
		(fp_line
			(start -0.508 -0.3048)
			(end -0.508 0.3048)
			(stroke
				(width 0.1)
				(type default)
			)
			(layer "F.Fab")
		)
		(pad "1" smd rect
			(at -0.5334 0 180)
			(size 0.7112 0.6096)
			(layers "F.Cu" "F.Mask" "F.Paste")
			(net "XP5R0V")
		)
		(pad "2" smd rect
			(at 0.5334 0 180)
			(size 0.7112 0.6096)
			(layers "F.Cu" "F.Mask" "F.Paste")
			(net "SG")
		)
		(zone
			(layer "F.Cu")
			(hatch none 0.5)
			(connect_pads
				(clearance 0)
			)
			(min_thickness 0.25)
			(keepout
				(tracks allowed)
				(vias not_allowed)
				(pads allowed)
				(copperpour not_allowed)
				(footprints allowed)
			)
			(placement
				(enabled no)
				(sheetname "")
			)
			(fill
				(thermal_gap 0.5)
				(thermal_bridge_width 0.5)
				(island_removal_mode 0)
			)
			(polygon
				(pts
					(xy 129.8702 -96.1898) (xy 129.7178 -96.1898) (xy 129.7178 -95.5802) (xy 129.8702 -95.5802)
				)
			)
		)
	)
	(footprint ""
		(layer "F.Cu")
		(at 44.704 -80.264 -90)
		(property "Reference" "L23"
			(at -0.1905 -3.84937 90)
			(unlocked yes)
			(layer "F.SilkS")
			(effects
				(font
					(size 0.7874 0.5842)
					(thickness 0.1524)
				)
				(justify left)
			)
		)
		(property "Value" "VAL*"
			(at -0.9398 3.70967 270)
			(unlocked yes)
			(layer "F.Fab")
			(hide yes)
			(effects
				(font
					(size 0.7874 0.5842)
					(thickness 0.1524)
				)
				(justify left)
			)
		)
		(property "Tolerance" "TOL*"
			(at -0.9906 5.00507 270)
			(unlocked yes)
			(layer "Cmts.User")
			(hide yes)
			(effects
				(font
					(size 0.7874 0.5842)
					(thickness 0.1524)
				)
				(justify left)
			)
		)
		(property "User Part Number" "PARTNUM*"
			(at -2.54 2.46507 270)
			(unlocked yes)
			(layer "Cmts.User")
			(hide yes)
			(effects
				(font
					(size 0.7874 0.5842)
					(thickness 0.1524)
				)
				(justify left)
			)
		)
		(property "Device Type" "FERRITEBEAD-G191-10101-01,26OHA"
			(at -0.9906 1.22047 270)
			(unlocked yes)
			(layer "F.Fab")
			(hide yes)
			(effects
				(font
					(size 0.7874 0.5842)
					(thickness 0.1524)
				)
				(justify left)
			)
		)
		(duplicate_pad_numbers_are_jumpers no)
		(fp_line
			(start -1.3208 0.7112)
			(end -1.3208 -0.7112)
			(stroke
				(width 0.1)
				(type default)
			)
			(layer "F.SilkS")
		)
		(fp_line
			(start 1.3208 0.7112)
			(end -1.3208 0.7112)
			(stroke
				(width 0.1)
				(type default)
			)
			(layer "F.SilkS")
		)
		(fp_line
			(start -1.3208 -0.7112)
			(end 1.3208 -0.7112)
			(stroke
				(width 0.1)
				(type default)
			)
			(layer "F.SilkS")
		)
		(fp_line
			(start 1.3208 -0.7112)
			(end 1.3208 0.7112)
			(stroke
				(width 0.1)
				(type default)
			)
			(layer "F.SilkS")
		)
		(fp_rect
			(start -1.3208 0.7112)
			(end 1.3208 -0.7112)
			(stroke
				(width 0)
				(type default)
			)
			(fill no)
			(layer "F.CrtYd")
		)
		(fp_line
			(start -0.8128 0.4572)
			(end -0.8128 -0.4572)
			(stroke
				(width 0.1)
				(type default)
			)
			(layer "F.Fab")
		)
		(fp_line
			(start 0.8128 0.4572)
			(end -0.8128 0.4572)
			(stroke
				(width 0.1)
				(type default)
			)
			(layer "F.Fab")
		)
		(fp_line
			(start -0.8128 -0.4572)
			(end 0.8128 -0.4572)
			(stroke
				(width 0.1)
				(type default)
			)
			(layer "F.Fab")
		)
		(fp_line
			(start 0.8128 -0.4572)
			(end 0.8128 0.4572)
			(stroke
				(width 0.1)
				(type default)
			)
			(layer "F.Fab")
		)
		(pad "1" smd rect
			(at -0.6858 0 270)
			(size 0.762 0.8636)
			(layers "F.Cu" "F.Mask" "F.Paste")
			(net "UNNAMED_525_CAPACITOR_I7_1")
		)
		(pad "2" smd rect
			(at 0.6858 0 270)
			(size 0.762 0.8636)
			(layers "F.Cu" "F.Mask" "F.Paste")
			(net "UNNAMED_525_CAPACITOR_I16_1")
		)
		(zone
			(layer "F.Cu")
			(hatch none 0.5)
			(connect_pads
				(clearance 0)
			)
			(min_thickness 0.25)
			(keepout
				(tracks not_allowed)
				(vias allowed)
				(pads allowed)
				(copperpour not_allowed)
				(footprints allowed)
			)
			(placement
				(enabled no)
				(sheetname "")
			)
			(fill
				(thermal_gap 0.5)
				(thermal_bridge_width 0.5)
				(island_removal_mode 0)
			)
			(polygon
				(pts
					(xy 44.2468 -80.4164) (xy 44.2468 -80.1116) (xy 45.1612 -80.1116) (xy 45.1612 -80.4164)
				)
			)
		)
		(zone
			(layer "F.Cu")
			(hatch none 0.5)
			(connect_pads
				(clearance 0)
			)
			(min_thickness 0.25)
			(keepout
				(tracks allowed)
				(vias not_allowed)
				(pads allowed)
				(copperpour not_allowed)
				(footprints allowed)
			)
			(placement
				(enabled no)
				(sheetname "")
			)
			(fill
				(thermal_gap 0.5)
				(thermal_bridge_width 0.5)
				(island_removal_mode 0)
			)
			(polygon
				(pts
					(xy 44.2468 -80.4164) (xy 44.2468 -80.1116) (xy 45.1612 -80.1116) (xy 45.1612 -80.4164)
				)
			)
		)
	)
	(footprint ""
		(layer "F.Cu")
		(at 13.899896 -32.599884 -90)
		(property "Reference" "U13"
			(at 1.738884 -2.649474 90)
			(unlocked yes)
			(layer "F.SilkS")
			(effects
				(font
					(size 0.7874 0.5842)
					(thickness 0.1524)
				)
			)
		)
		(property "Value" ""
			(at 0 0 270)
			(layer "F.Fab")
			(effects
				(font
					(size 1.27 1.27)
				)
			)
		)
		(property "Device Type" "74HCT2G125DP_TSSOP8-G220-00055A"
			(at 0 2.413 270)
			(unlocked yes)
			(layer "F.Fab")
			(hide yes)
			(effects
				(font
					(size 0.7874 0.5842)
					(thickness 0.1524)
				)
			)
		)
		(property "User Part Number" "PARTNUM*"
			(at 0 3.6068 270)
			(unlocked yes)
			(layer "Cmts.User")
			(hide yes)
			(effects
				(font
					(size 0.7874 0.5842)
					(thickness 0.1524)
				)
			)
		)
		(duplicate_pad_numbers_are_jumpers no)
		(fp_line
			(start -2.426716 1.304036)
			(end -2.426716 -1.304036)
			(stroke
				(width 0.1)
				(type default)
			)
			(layer "F.SilkS")
		)
		(fp_line
			(start 2.426716 1.304036)
			(end -2.426716 1.304036)
			(stroke
				(width 0.1)
				(type default)
			)
			(layer "F.SilkS")
		)
		(fp_line
			(start -2.426716 -1.304036)
			(end 2.426716 -1.304036)
			(stroke
				(width 0.1)
				(type default)
			)
			(layer "F.SilkS")
		)
		(fp_line
			(start 2.426716 -1.304036)
			(end 2.426716 1.304036)
			(stroke
				(width 0.1)
				(type default)
			)
			(layer "F.SilkS")
		)
		(fp_poly
			(pts
				(arc
					(start -3.21437 -1.465326)
					(mid -3.21437 -0.703326)
					(end -3.21437 -1.465326)
				)
			)
			(stroke
				(width 0)
				(type default)
			)
			(fill yes)
			(layer "F.SilkS")
		)
		(fp_poly
			(pts
				(xy -2.680716 1.558036) (xy 2.680716 1.558036) (xy 2.680716 -1.558036) (xy -2.680716 -1.558036)
			)
			(stroke
				(width 0)
				(type default)
			)
			(fill no)
			(layer "F.CrtYd")
		)
		(fp_line
			(start -1.199896 1.050036)
			(end 1.199896 1.050036)
			(stroke
				(width 0.1)
				(type default)
			)
			(layer "F.Fab")
		)
		(fp_line
			(start 1.199896 1.050036)
			(end 1.199896 -1.050036)
			(stroke
				(width 0.1)
				(type default)
			)
			(layer "F.Fab")
		)
		(fp_line
			(start -1.199896 -1.050036)
			(end -1.199896 1.050036)
			(stroke
				(width 0.1)
				(type default)
			)
			(layer "F.Fab")
		)
		(fp_line
			(start 1.199896 -1.050036)
			(end -1.199896 -1.050036)
			(stroke
				(width 0.1)
				(type default)
			)
			(layer "F.Fab")
		)
		(fp_poly
			(pts
				(arc
					(start -1.94437 -1.211326)
					(mid -1.94437 -0.449326)
					(end -1.94437 -1.211326)
				)
			)
			(stroke
				(width 0)
				(type default)
			)
			(fill yes)
			(layer "F.Fab")
		)
		(fp_text user "4"
			(at -1.813052 1.834896 0)
			(unlocked yes)
			(layer "F.SilkS")
			(effects
				(font
					(size 0.635 0.4064)
					(thickness 0.1524)
				)
			)
		)
		(fp_text user "5"
			(at 2.913634 1.453896 0)
			(unlocked yes)
			(layer "F.SilkS")
			(effects
				(font
					(size 0.635 0.4064)
					(thickness 0.1524)
				)
			)
		)
		(fp_text user "8"
			(at 2.913634 -1.340104 0)
			(unlocked yes)
			(layer "F.SilkS")
			(effects
				(font
					(size 0.635 0.4064)
					(thickness 0.1524)
				)
			)
		)
		(fp_text user "4"
			(at -1.767332 0.945896 0)
			(unlocked yes)
			(layer "F.Fab")
			(effects
				(font
					(size 0.7874 0.5842)
					(thickness 0.1524)
				)
			)
		)
		(fp_text user "5"
			(at 1.947926 0.710184 0)
			(unlocked yes)
			(layer "F.Fab")
			(effects
				(font
					(size 0.7874 0.5842)
					(thickness 0.1524)
				)
			)
		)
		(fp_text user "8"
			(at 1.96088 -0.910844 0)
			(unlocked yes)
			(layer "F.Fab")
			(effects
				(font
					(size 0.7874 0.5842)
					(thickness 0.1524)
				)
			)
		)
		(pad "1" smd rect
			(at -1.690116 -0.749808 270)
			(size 0.9652 0.3048)
			(layers "F.Cu" "F.Mask" "F.Paste")
			(net "SMA3_SIG_OUT_BF_EN_N")
		)
		(pad "2" smd rect
			(at -1.690116 -0.249936 270)
			(size 0.9652 0.3048)
			(layers "F.Cu" "F.Mask" "F.Paste")
			(net "UNNAMED_12_74HCT2G125DPTSSOP8_I")
		)
		(pad "3" smd rect
			(at -1.690116 0.249936 270)
			(size 0.9652 0.3048)
			(layers "F.Cu" "F.Mask" "F.Paste")
			(net "BF_ANT3_IN")
		)
		(pad "4" smd rect
			(at -1.690116 0.749808 270)
			(size 0.9652 0.3048)
			(layers "F.Cu" "F.Mask" "F.Paste")
			(net "SG")
		)
		(pad "5" smd rect
			(at 1.690116 0.749808 270)
			(size 0.9652 0.3048)
			(layers "F.Cu" "F.Mask" "F.Paste")
			(net "BF_SMA3_SIG_IO_CONN")
		)
		(pad "6" smd rect
			(at 1.690116 0.249936 270)
			(size 0.9652 0.3048)
			(layers "F.Cu" "F.Mask" "F.Paste")
			(net "BF_SMA3_SIG_IO_CONN")
		)
		(pad "7" smd rect
			(at 1.690116 -0.249936 270)
			(size 0.9652 0.3048)
			(layers "F.Cu" "F.Mask" "F.Paste")
			(net "SMA3_SIG_IN_BF_EN_N")
		)
		(pad "8" smd rect
			(at 1.690116 -0.749808 270)
			(size 0.9652 0.3048)
			(layers "F.Cu" "F.Mask" "F.Paste")
			(net "XP3R3V_FPGA")
		)
	)
	(footprint ""
		(layer "F.Cu")
		(at 13.843 -43.434)
		(property "Reference" "TP29"
			(at 0.7366 -0.60325 0)
			(unlocked yes)
			(layer "F.SilkS")
			(effects
				(font
					(size 0.635 0.4064)
					(thickness 0.1524)
				)
				(justify left)
			)
		)
		(property "Value" ""
			(at 0 0 0)
			(layer "F.Fab")
			(effects
				(font
					(size 1.27 1.27)
				)
			)
		)
		(property "Device Type" "TP_PIONT-TP010CT020B030_PTH-TPA"
			(at -1.341882 0.996696 0)
			(unlocked yes)
			(layer "F.Fab")
			(hide yes)
			(effects
				(font
					(size 0.7874 0.5842)
					(thickness 0.000001)
				)
				(justify left)
			)
		)
		(duplicate_pad_numbers_are_jumpers no)
		(fp_poly
			(pts
				(arc
					(start 0.889 0)
					(mid -0.889 0)
					(end 0.889 0)
				)
			)
			(stroke
				(width 0)
				(type default)
			)
			(fill no)
			(layer "B.CrtYd")
		)
		(fp_poly
			(pts
				(arc
					(start 0.889 0)
					(mid -0.889 0)
					(end 0.889 0)
				)
			)
			(stroke
				(width 0)
				(type default)
			)
			(fill no)
			(layer "F.CrtYd")
		)
		(pad "1" thru_hole circle
			(at 0 0)
			(size 0.508 0.508)
			(drill 0.254)
			(layers "*.Cu" "*.Mask")
			(remove_unused_layers no)
			(net "SMA2_SIG_IN_BF_EN_N")
			(clearance 0.1016)
			(padstack
				(mode front_inner_back)
				(layer "Inner"
					(shape circle)
					(size 0.508 0.508)
					(clearance 0.1016)
				)
				(layer "B.Cu"
					(shape circle)
					(size 0.762 0.762)
					(clearance -0.0254)
				)
			)
		)
	)
)
